# T6G (Grand Teton) — schematic netlist excerpt (pin names and nets, part order shuffled) for the footprints in the layout excerpt that follows; sources: Cadence DE-HDL packaged netlist, KiCad conversion of 04192023_DAF0TMB3IC0_F0TG_MB_C_brd_V02_OCP.brd

R4180  Q_RES  33.2 1% CHIP  pkg 0402LF  page 235 : A = SMB_LM75_0_3V3AUX_SCL ; B = SMB_LM75_0_3V3AUX_SCL_R1
R664  Q_RES  0 5% EMPTY  pkg 0402LF  page 334 : A = P1V8_CPU1_RT1_1A_1D ; B = P1V8_CPU1_RT1_1A

(kicad_pcb
	(version 20260206)
	(generator "pcbnew")
	(generator_version "10.0")
	(general
		(thickness 1.6)
		(legacy_teardrops no)
	)
	(paper "A4")
	(title_block
		(title "04192023_DAF0TMB3IC0_F0TG_MB_C_brd_V02_OCP.brd")
		(comment 1 "Grand Teton / footprints 1533-1534 of 8354")
	)
	(layers
		(0 "F.Cu" signal "TOP")
		(4 "In1.Cu" signal "GND")
		(6 "In2.Cu" signal "IN1")
		(8 "In3.Cu" signal "GND1")
		(10 "In4.Cu" signal "IN2")
		(12 "In5.Cu" signal "GND2")
		(14 "In6.Cu" signal "IN3")
		(16 "In7.Cu" signal "GND3")
		(18 "In8.Cu" signal "VCC")
		(20 "In9.Cu" signal "VCC1")
		(22 "In10.Cu" signal "GND4")
		(24 "In11.Cu" signal "IN4")
		(26 "In12.Cu" signal "GND5")
		(28 "In13.Cu" signal "IN5")
		(30 "In14.Cu" signal "GND6")
		(32 "In15.Cu" signal "IN6")
		(34 "In16.Cu" signal "GND7")
		(2 "B.Cu" signal "BOTTOM")
		(9 "F.Adhes" user "F.Adhesive")
		(11 "B.Adhes" user "B.Adhesive")
		(13 "F.Paste" user "Package Geometry/Pastemask Top")
		(15 "B.Paste" user "Package Geometry/Pastemask Bottom")
		(5 "F.SilkS" user "Ref Des/Silkscreen Top")
		(7 "B.SilkS" user "Ref Des/Silkscreen Bottom")
		(1 "F.Mask" user "Board Geometry/Soldermask Top")
		(3 "B.Mask" user "Board Geometry/Soldermask Bottom")
		(17 "Dwgs.User" user "User.Drawings")
		(19 "Cmts.User" user "User.Comments")
		(21 "Eco1.User" user "User.Eco1")
		(23 "Eco2.User" user "User.Eco2")
		(25 "Edge.Cuts" user "Board Geometry/Outline")
		(27 "Margin" user)
		(31 "F.CrtYd" user "Package Geometry/Place Bound Top")
		(29 "B.CrtYd" user "Package Geometry/Place Bound Bottom")
		(35 "F.Fab" user "Ref Des/Assembly Top")
		(33 "B.Fab" user "Ref Des/Assembly Bottom")
	)
	(footprint ""
		(layer "F.Cu")
		(at 102.390194 -385.09448 180)
		(property "Reference" "R664"
			(at 0 0 180)
			(layer "F.SilkS")
			(hide yes)
			(effects
				(font
					(size 1.27 1.27)
				)
			)
		)
		(property "Value" ""
			(at 0 0 180)
			(layer "F.Fab")
			(effects
				(font
					(size 1.27 1.27)
				)
			)
		)
		(duplicate_pad_numbers_are_jumpers no)
		(fp_line
			(start 0.7874 0.4064)
			(end -0.7874 0.4064)
			(stroke
				(width 0.1524)
				(type default)
			)
			(layer "F.SilkS")
		)
		(fp_line
			(start 0.7874 -0.4064)
			(end 0.7874 0.4064)
			(stroke
				(width 0.1524)
				(type default)
			)
			(layer "F.SilkS")
		)
		(fp_line
			(start -0.7874 0.4064)
			(end -0.7874 -0.4064)
			(stroke
				(width 0.1524)
				(type default)
			)
			(layer "F.SilkS")
		)
		(fp_line
			(start -0.7874 -0.4064)
			(end 0.7874 -0.4064)
			(stroke
				(width 0.1524)
				(type default)
			)
			(layer "F.SilkS")
		)
		(fp_line
			(start 0.67945 0.3048)
			(end 0.120396 0.3048)
			(stroke
				(width 0.1)
				(type default)
			)
			(layer "F.Fab")
		)
		(fp_line
			(start 0.67945 -0.3048)
			(end 0.67945 0.3048)
			(stroke
				(width 0.1)
				(type default)
			)
			(layer "F.Fab")
		)
		(fp_line
			(start 0.12065 -0.2794)
			(end 0.12065 -0.3048)
			(stroke
				(width 0.1)
				(type default)
			)
			(layer "F.Fab")
		)
		(fp_line
			(start 0.12065 -0.3048)
			(end 0.67945 -0.3048)
			(stroke
				(width 0.1)
				(type default)
			)
			(layer "F.Fab")
		)
		(fp_line
			(start 0.120396 0.3048)
			(end 0.120396 0.2794)
			(stroke
				(width 0.1)
				(type default)
			)
			(layer "F.Fab")
		)
		(fp_line
			(start 0.120396 0.2794)
			(end -0.12065 0.2794)
			(stroke
				(width 0.1)
				(type default)
			)
			(layer "F.Fab")
		)
		(fp_line
			(start -0.12065 0.3048)
			(end -0.67945 0.3048)
			(stroke
				(width 0.1)
				(type default)
			)
			(layer "F.Fab")
		)
		(fp_line
			(start -0.12065 0.2794)
			(end -0.12065 0.3048)
			(stroke
				(width 0.1)
				(type default)
			)
			(layer "F.Fab")
		)
		(fp_line
			(start -0.12065 -0.2794)
			(end 0.12065 -0.2794)
			(stroke
				(width 0.1)
				(type default)
			)
			(layer "F.Fab")
		)
		(fp_line
			(start -0.12065 -0.305054)
			(end -0.12065 -0.2794)
			(stroke
				(width 0.1)
				(type default)
			)
			(layer "F.Fab")
		)
		(fp_line
			(start -0.67945 0.3048)
			(end -0.67945 -0.305054)
			(stroke
				(width 0.1)
				(type default)
			)
			(layer "F.Fab")
		)
		(fp_line
			(start -0.67945 -0.305054)
			(end -0.12065 -0.305054)
			(stroke
				(width 0.1)
				(type default)
			)
			(layer "F.Fab")
		)
		(pad "1" smd rect
			(at -0.40005 0)
			(size 0.4572 0.508)
			(layers "F.Cu" "F.Mask" "F.Paste")
			(net "P1V8_CPU1_RT1_1A_1D")
		)
		(pad "2" smd rect
			(at 0.40005 0)
			(size 0.4572 0.508)
			(layers "F.Cu" "F.Mask" "F.Paste")
			(net "P1V8_CPU1_RT1_1A")
		)
	)
	(footprint ""
		(layer "F.Cu")
		(at 367.157 -413.639 90)
		(property "Reference" "R4180"
			(at 0 0 90)
			(layer "F.SilkS")
			(hide yes)
			(effects
				(font
					(size 1.27 1.27)
				)
			)
		)
		(property "Value" ""
			(at 0 0 90)
			(layer "F.Fab")
			(effects
				(font
					(size 1.27 1.27)
				)
			)
		)
		(duplicate_pad_numbers_are_jumpers no)
		(fp_line
			(start 0.7874 -0.4064)
			(end 0.7874 0.4064)
			(stroke
				(width 0.1524)
				(type default)
			)
			(layer "F.SilkS")
		)
		(fp_line
			(start -0.7874 -0.4064)
			(end 0.7874 -0.4064)
			(stroke
				(width 0.1524)
				(type default)
			)
			(layer "F.SilkS")
		)
		(fp_line
			(start 0.7874 0.4064)
			(end -0.7874 0.4064)
			(stroke
				(width 0.1524)
				(type default)
			)
			(layer "F.SilkS")
		)
		(fp_line
			(start -0.7874 0.4064)
			(end -0.7874 -0.4064)
			(stroke
				(width 0.1524)
				(type default)
			)
			(layer "F.SilkS")
		)
		(fp_line
			(start -0.12065 -0.305054)
			(end -0.12065 -0.2794)
			(stroke
				(width 0.1)
				(type default)
			)
			(layer "F.Fab")
		)
		(fp_line
			(start -0.67945 -0.305054)
			(end -0.12065 -0.305054)
			(stroke
				(width 0.1)
				(type default)
			)
			(layer "F.Fab")
		)
		(fp_line
			(start 0.67945 -0.3048)
			(end 0.67945 0.3048)
			(stroke
				(width 0.1)
				(type default)
			)
			(layer "F.Fab")
		)
		(fp_line
			(start 0.12065 -0.3048)
			(end 0.67945 -0.3048)
			(stroke
				(width 0.1)
				(type default)
			)
			(layer "F.Fab")
		)
		(fp_line
			(start 0.12065 -0.2794)
			(end 0.12065 -0.3048)
			(stroke
				(width 0.1)
				(type default)
			)
			(layer "F.Fab")
		)
		(fp_line
			(start -0.12065 -0.2794)
			(end 0.12065 -0.2794)
			(stroke
				(width 0.1)
				(type default)
			)
			(layer "F.Fab")
		)
		(fp_line
			(start 0.120396 0.2794)
			(end -0.12065 0.2794)
			(stroke
				(width 0.1)
				(type default)
			)
			(layer "F.Fab")
		)
		(fp_line
			(start -0.12065 0.2794)
			(end -0.12065 0.3048)
			(stroke
				(width 0.1)
				(type default)
			)
			(layer "F.Fab")
		)
		(fp_line
			(start 0.67945 0.3048)
			(end 0.120396 0.3048)
			(stroke
				(width 0.1)
				(type default)
			)
			(layer "F.Fab")
		)
		(fp_line
			(start 0.120396 0.3048)
			(end 0.120396 0.2794)
			(stroke
				(width 0.1)
				(type default)
			)
			(layer "F.Fab")
		)
		(fp_line
			(start -0.12065 0.3048)
			(end -0.67945 0.3048)
			(stroke
				(width 0.1)
				(type default)
			)
			(layer "F.Fab")
		)
		(fp_line
			(start -0.67945 0.3048)
			(end -0.67945 -0.305054)
			(stroke
				(width 0.1)
				(type default)
			)
			(layer "F.Fab")
		)
		(pad "1" smd circle
			(at -0.40005 0 90)
			(size 0 0)
			(layers "F.Cu" "F.Mask" "F.Paste")
			(net "SMB_LM75_0_3V3AUX_SCL")
		)
		(pad "2" smd circle
			(at 0.40005 0 90)
			(size 0 0)
			(layers "F.Cu" "F.Mask" "F.Paste")
			(net "SMB_LM75_0_3V3AUX_SCL_R1")
		)
	)
)
